# S9S_MB_2U (Grand Teton) — schematic netlist excerpt (pin names and nets, part order shuffled) for the footprints in the layout excerpt that follows; sources: Cadence DE-HDL packaged netlist, KiCad conversion of 03242023_DA0F0TMBIJ0_F0T_Motherboard_J_brd_V01_OCP.brd

R1274  Q_RES  22 1% CHIP  pkg 0402LF  page 209 : A = CLK_100M_OCP_SFF_2_R_DN ; B = CLK_100M_OCP_SFF_2_DN
D96  Q_LED  IC  pkg SMLF  page 252 : A = LED_PWRGD_PS_PWROK_PLD ; C = LED_PWRGD_PS_PWROK_PLD_D

(kicad_pcb
	(version 20260206)
	(generator "pcbnew")
	(generator_version "10.0")
	(general
		(thickness 1.6)
		(legacy_teardrops no)
	)
	(paper "A4")
	(title_block
		(title "03242023_DA0F0TMBIJ0_F0T_Motherboard_J_brd_V01_OCP.brd")
		(comment 1 "Grand Teton / footprints 2480-2481 of 6105")
	)
	(layers
		(0 "F.Cu" signal "TOP")
		(4 "In1.Cu" signal "GND")
		(6 "In2.Cu" signal "IN1")
		(8 "In3.Cu" signal "GND1")
		(10 "In4.Cu" signal "IN2")
		(12 "In5.Cu" signal "GND2")
		(14 "In6.Cu" signal "IN3")
		(16 "In7.Cu" signal "GND3")
		(18 "In8.Cu" signal "VCC")
		(20 "In9.Cu" signal "VCC1")
		(22 "In10.Cu" signal "GND4")
		(24 "In11.Cu" signal "IN4")
		(26 "In12.Cu" signal "GND5")
		(28 "In13.Cu" signal "IN5")
		(30 "In14.Cu" signal "GND6")
		(32 "In15.Cu" signal "IN6")
		(34 "In16.Cu" signal "GND7")
		(2 "B.Cu" signal "BOTTOM")
		(9 "F.Adhes" user "F.Adhesive")
		(11 "B.Adhes" user "B.Adhesive")
		(13 "F.Paste" user "Package Geometry/Pastemask Top")
		(15 "B.Paste" user "Package Geometry/Pastemask Bottom")
		(5 "F.SilkS" user "Ref Des/Silkscreen Top")
		(7 "B.SilkS" user "Ref Des/Silkscreen Bottom")
		(1 "F.Mask" user "Board Geometry/Soldermask Top")
		(3 "B.Mask" user "Board Geometry/Soldermask Bottom")
		(17 "Dwgs.User" user "User.Drawings")
		(19 "Cmts.User" user "User.Comments")
		(21 "Eco1.User" user "User.Eco1")
		(23 "Eco2.User" user "User.Eco2")
		(25 "Edge.Cuts" user "Board Geometry/Outline")
		(27 "Margin" user)
		(31 "F.CrtYd" user "Package Geometry/Place Bound Top")
		(29 "B.CrtYd" user "Package Geometry/Place Bound Bottom")
		(35 "F.Fab" user "Ref Des/Assembly Top")
		(33 "B.Fab" user "Ref Des/Assembly Bottom")
	)
	(footprint ""
		(layer "F.Cu")
		(at 228.816662 -122.151902 180)
		(property "Reference" "R1274"
			(at 0 0 180)
			(layer "F.SilkS")
			(hide yes)
			(effects
				(font
					(size 1.27 1.27)
				)
			)
		)
		(property "Value" ""
			(at 0 0 180)
			(layer "F.Fab")
			(effects
				(font
					(size 1.27 1.27)
				)
			)
		)
		(duplicate_pad_numbers_are_jumpers no)
		(fp_line
			(start 0.7874 -0.4064)
			(end 0.7874 0.164338)
			(stroke
				(width 0.1524)
				(type default)
			)
			(layer "F.SilkS")
		)
		(fp_line
			(start 0.610362 0.4064)
			(end -0.507238 0.4064)
			(stroke
				(width 0.1524)
				(type default)
			)
			(layer "F.SilkS")
		)
		(fp_line
			(start -0.7874 0.067818)
			(end -0.7874 -0.4064)
			(stroke
				(width 0.1524)
				(type default)
			)
			(layer "F.SilkS")
		)
		(fp_line
			(start -0.7874 -0.4064)
			(end 0.7874 -0.4064)
			(stroke
				(width 0.1524)
				(type default)
			)
			(layer "F.SilkS")
		)
		(fp_line
			(start 0.67945 0.3048)
			(end 0.120396 0.3048)
			(stroke
				(width 0.1)
				(type default)
			)
			(layer "F.Fab")
		)
		(fp_line
			(start 0.67945 -0.3048)
			(end 0.67945 0.3048)
			(stroke
				(width 0.1)
				(type default)
			)
			(layer "F.Fab")
		)
		(fp_line
			(start 0.12065 -0.2794)
			(end 0.12065 -0.3048)
			(stroke
				(width 0.1)
				(type default)
			)
			(layer "F.Fab")
		)
		(fp_line
			(start 0.12065 -0.3048)
			(end 0.67945 -0.3048)
			(stroke
				(width 0.1)
				(type default)
			)
			(layer "F.Fab")
		)
		(fp_line
			(start 0.120396 0.3048)
			(end 0.120396 0.2794)
			(stroke
				(width 0.1)
				(type default)
			)
			(layer "F.Fab")
		)
		(fp_line
			(start 0.120396 0.2794)
			(end -0.12065 0.2794)
			(stroke
				(width 0.1)
				(type default)
			)
			(layer "F.Fab")
		)
		(fp_line
			(start -0.12065 0.3048)
			(end -0.67945 0.3048)
			(stroke
				(width 0.1)
				(type default)
			)
			(layer "F.Fab")
		)
		(fp_line
			(start -0.12065 0.2794)
			(end -0.12065 0.3048)
			(stroke
				(width 0.1)
				(type default)
			)
			(layer "F.Fab")
		)
		(fp_line
			(start -0.12065 -0.2794)
			(end 0.12065 -0.2794)
			(stroke
				(width 0.1)
				(type default)
			)
			(layer "F.Fab")
		)
		(fp_line
			(start -0.12065 -0.305054)
			(end -0.12065 -0.2794)
			(stroke
				(width 0.1)
				(type default)
			)
			(layer "F.Fab")
		)
		(fp_line
			(start -0.67945 0.3048)
			(end -0.67945 -0.305054)
			(stroke
				(width 0.1)
				(type default)
			)
			(layer "F.Fab")
		)
		(fp_line
			(start -0.67945 -0.305054)
			(end -0.12065 -0.305054)
			(stroke
				(width 0.1)
				(type default)
			)
			(layer "F.Fab")
		)
		(pad "1" smd circle
			(at -0.40005 0 180)
			(size 0 0)
			(layers "F.Cu" "F.Mask" "F.Paste")
			(net "CLK_100M_OCP_SFF_2_R_DN")
		)
		(pad "2" smd circle
			(at 0.40005 0 180)
			(size 0 0)
			(layers "F.Cu" "F.Mask" "F.Paste")
			(net "CLK_100M_OCP_SFF_2_DN")
		)
	)
	(footprint ""
		(layer "F.Cu")
		(at 93.597476 -79.078836)
		(property "Reference" "D96"
			(at -47.22241 38.649402 90)
			(unlocked yes)
			(layer "F.SilkS")
			(effects
				(font
					(size 0.635 0.4064)
					(thickness 0.1524)
				)
				(justify left)
			)
		)
		(property "Value" ""
			(at 0 0 0)
			(layer "F.Fab")
			(effects
				(font
					(size 1.27 1.27)
				)
			)
		)
		(duplicate_pad_numbers_are_jumpers no)
		(fp_line
			(start -0.90678 0.4826)
			(end -0.90678 -0.4699)
			(stroke
				(width 0.1524)
				(type default)
			)
			(layer "F.SilkS")
		)
		(fp_line
			(start -0.89408 -0.4826)
			(end 0.90678 -0.4826)
			(stroke
				(width 0.1524)
				(type default)
			)
			(layer "F.SilkS")
		)
		(fp_line
			(start -0.79248 -0.4826)
			(end 1.03378 -0.4826)
			(stroke
				(width 0.1524)
				(type default)
			)
			(layer "F.SilkS")
		)
		(fp_line
			(start -0.64008 -0.4826)
			(end 1.16078 -0.4826)
			(stroke
				(width 0.1524)
				(type default)
			)
			(layer "F.SilkS")
		)
		(fp_line
			(start 0.90678 -0.4826)
			(end 0.90678 0.4826)
			(stroke
				(width 0.1524)
				(type default)
			)
			(layer "F.SilkS")
		)
		(fp_line
			(start 0.90678 0.4826)
			(end -0.90678 0.4826)
			(stroke
				(width 0.1524)
				(type default)
			)
			(layer "F.SilkS")
		)
		(fp_line
			(start 1.03378 -0.4826)
			(end 1.03378 0.4826)
			(stroke
				(width 0.1524)
				(type default)
			)
			(layer "F.SilkS")
		)
		(fp_line
			(start 1.03378 0.4826)
			(end -0.79248 0.4826)
			(stroke
				(width 0.1524)
				(type default)
			)
			(layer "F.SilkS")
		)
		(fp_line
			(start 1.16078 -0.4826)
			(end 1.16078 0.4826)
			(stroke
				(width 0.1524)
				(type default)
			)
			(layer "F.SilkS")
		)
		(fp_line
			(start 1.16078 0.4826)
			(end -0.64008 0.4826)
			(stroke
				(width 0.1524)
				(type default)
			)
			(layer "F.SilkS")
		)
		(fp_line
			(start -0.499872 -0.249936)
			(end 0.499872 -0.249936)
			(stroke
				(width 0.1)
				(type default)
			)
			(layer "F.Fab")
		)
		(fp_line
			(start -0.499872 0.249936)
			(end -0.499872 -0.249936)
			(stroke
				(width 0.1)
				(type default)
			)
			(layer "F.Fab")
		)
		(fp_line
			(start 0.499872 -0.249936)
			(end 0.499872 0.249936)
			(stroke
				(width 0.1)
				(type default)
			)
			(layer "F.Fab")
		)
		(fp_line
			(start 0.499872 0.249936)
			(end -0.499872 0.249936)
			(stroke
				(width 0.1)
				(type default)
			)
			(layer "F.Fab")
		)
		(pad "A" smd rect
			(at -0.47498 0)
			(size 0.6096 0.7112)
			(layers "F.Cu" "F.Mask" "F.Paste")
			(net "LED_PWRGD_PS_PWROK_PLD")
		)
		(pad "C" smd rect
			(at 0.47498 0)
			(size 0.6096 0.7112)
			(layers "F.Cu" "F.Mask" "F.Paste")
			(net "LED_PWRGD_PS_PWROK_PLD_D")
		)
	)
)
